(kicad_pcb
	(version 20260206)
	(generator "pcbnew")
	(generator_version "10.0")
	(general
		(thickness 1.6)
		(legacy_teardrops no)
	)
	(paper "A4")
	(title_block
		(title "12092022_DA0F0TMDCD0_F0T_Management_Board_D_brd_V3_OCP.brd")
		(comment 1 "Grand Teton / footprints 1160-1165 of 1440")
	)
	(layers
		(0 "F.Cu" signal "TOP")
		(4 "In1.Cu" signal "GND")
		(6 "In2.Cu" signal "IN1")
		(8 "In3.Cu" signal "GND1")
		(10 "In4.Cu" signal "IN2")
		(12 "In5.Cu" signal "VCC")
		(14 "In6.Cu" signal "VCC1")
		(16 "In7.Cu" signal "IN3")
		(18 "In8.Cu" signal "GND2")
		(20 "In9.Cu" signal "IN4")
		(22 "In10.Cu" signal "GND3")
		(2 "B.Cu" signal "BOTTOM")
		(9 "F.Adhes" user "F.Adhesive")
		(11 "B.Adhes" user "B.Adhesive")
		(13 "F.Paste" user "Package Geometry/Pastemask Top")
		(15 "B.Paste" user "Package Geometry/Pastemask Bottom")
		(5 "F.SilkS" user "Ref Des/Silkscreen Top")
		(7 "B.SilkS" user "Ref Des/Silkscreen Bottom")
		(1 "F.Mask" user "Board Geometry/Soldermask Top")
		(3 "B.Mask" user "Board Geometry/Soldermask Bottom")
		(17 "Dwgs.User" user "User.Drawings")
		(19 "Cmts.User" user "User.Comments")
		(21 "Eco1.User" user "User.Eco1")
		(23 "Eco2.User" user "User.Eco2")
		(25 "Edge.Cuts" user "Board Geometry/Outline")
		(27 "Margin" user)
		(31 "F.CrtYd" user "Package Geometry/Place Bound Top")
		(29 "B.CrtYd" user "Package Geometry/Place Bound Bottom")
		(35 "F.Fab" user "Ref Des/Assembly Top")
		(33 "B.Fab" user "Ref Des/Assembly Bottom")
	)
	(footprint ""
		(layer "B.Cu")
		(at 7.9756 -27.7368)
		(property "Reference" "U24"
			(at 0.9652 -1.80213 0)
			(unlocked yes)
			(layer "B.SilkS")
			(effects
				(font
					(size 0.7874 0.5842)
					(thickness 0.1524)
				)
				(justify left mirror)
			)
		)
		(property "Value" ""
			(at 0 0 0)
			(layer "B.Fab")
			(effects
				(font
					(size 1.27 1.27)
				)
				(justify mirror)
			)
		)
		(duplicate_pad_numbers_are_jumpers no)
		(fp_line
			(start -1.38176 -1.100074)
			(end -0.592074 -1.100074)
			(stroke
				(width 0.1524)
				(type default)
			)
			(layer "B.SilkS")
		)
		(fp_line
			(start -1.38176 1.100074)
			(end -1.38176 -1.100074)
			(stroke
				(width 0.1524)
				(type default)
			)
			(layer "B.SilkS")
		)
		(fp_line
			(start -0.592074 -1.100074)
			(end 0 -0.508)
			(stroke
				(width 0.1524)
				(type default)
			)
			(layer "B.SilkS")
		)
		(fp_line
			(start 0 -0.508)
			(end 0.592074 -1.100074)
			(stroke
				(width 0.1524)
				(type default)
			)
			(layer "B.SilkS")
		)
		(fp_line
			(start 0.592074 -1.100074)
			(end 1.38176 -1.100074)
			(stroke
				(width 0.1524)
				(type default)
			)
			(layer "B.SilkS")
		)
		(fp_line
			(start 1.38176 -1.100074)
			(end 1.38176 1.100074)
			(stroke
				(width 0.1524)
				(type default)
			)
			(layer "B.SilkS")
		)
		(fp_line
			(start 1.38176 1.100074)
			(end -1.38176 1.100074)
			(stroke
				(width 0.1524)
				(type default)
			)
			(layer "B.SilkS")
		)
		(fp_poly
			(pts
				(xy 1.9431 -0.870204) (xy 1.50241 -0.649986) (xy 1.9431 -0.429768)
			)
			(stroke
				(width 0)
				(type default)
			)
			(fill yes)
			(layer "B.SilkS")
		)
		(fp_line
			(start -0.674878 -1.100074)
			(end 0.674878 -1.100074)
			(stroke
				(width 0.1)
				(type default)
			)
			(layer "B.Fab")
		)
		(fp_line
			(start -0.674878 1.100074)
			(end -0.674878 -1.100074)
			(stroke
				(width 0.1)
				(type default)
			)
			(layer "B.Fab")
		)
		(fp_line
			(start 0.674878 -1.100074)
			(end 0.674878 1.100074)
			(stroke
				(width 0.1)
				(type default)
			)
			(layer "B.Fab")
		)
		(fp_line
			(start 0.674878 1.100074)
			(end -0.674878 1.100074)
			(stroke
				(width 0.1)
				(type default)
			)
			(layer "B.Fab")
		)
		(fp_poly
			(pts
				(xy 1.9431 -0.870204) (xy 1.50241 -0.649986) (xy 1.9431 -0.429768)
			)
			(stroke
				(width 0)
				(type default)
			)
			(fill yes)
			(layer "B.Fab")
		)
		(pad "1" smd rect
			(at 0.94996 -0.649986 270)
			(size 0.4318 0.6096)
			(layers "B.Cu" "B.Mask" "B.Paste")
			(net "UART_BMC_5_TXD_BUF1_R")
		)
		(pad "2" smd rect
			(at 0.94996 0 270)
			(size 0.4318 0.6096)
			(layers "B.Cu" "B.Mask" "B.Paste")
			(net "GND")
		)
		(pad "3" smd rect
			(at 0.94996 0.649986 270)
			(size 0.4318 0.6096)
			(layers "B.Cu" "B.Mask" "B.Paste")
			(net "UART_BMC_5_RXD_BUF")
		)
		(pad "4" smd rect
			(at -0.94996 0.649986 270)
			(size 0.4318 0.6096)
			(layers "B.Cu" "B.Mask" "B.Paste")
			(net "UART_BMC_5_RXD_BUF_R")
		)
		(pad "5" smd rect
			(at -0.94996 0 270)
			(size 0.4318 0.6096)
			(layers "B.Cu" "B.Mask" "B.Paste")
			(net "P3V3_AUX")
		)
		(pad "6" smd rect
			(at -0.94996 -0.649986 270)
			(size 0.4318 0.6096)
			(layers "B.Cu" "B.Mask" "B.Paste")
			(net "UART_BMC_5_TXD_BUF")
		)
	)
	(footprint ""
		(layer "B.Cu")
		(at 58.890662 -71.082662)
		(property "Reference" "C314"
			(at 0 0 0)
			(layer "B.SilkS")
			(hide yes)
			(effects
				(font
					(size 1.27 1.27)
				)
				(justify mirror)
			)
		)
		(property "Value" ""
			(at 0 0 0)
			(layer "B.Fab")
			(effects
				(font
					(size 1.27 1.27)
				)
				(justify mirror)
			)
		)
		(duplicate_pad_numbers_are_jumpers no)
		(fp_line
			(start -0.7874 -0.4064)
			(end -0.7874 0.4064)
			(stroke
				(width 0.1524)
				(type default)
			)
			(layer "B.SilkS")
		)
		(fp_line
			(start -0.7874 0.4064)
			(end 0.7874 0.4064)
			(stroke
				(width 0.1524)
				(type default)
			)
			(layer "B.SilkS")
		)
		(fp_line
			(start 0.7874 -0.4064)
			(end -0.7874 -0.4064)
			(stroke
				(width 0.1524)
				(type default)
			)
			(layer "B.SilkS")
		)
		(fp_line
			(start 0.7874 0.4064)
			(end 0.7874 -0.4064)
			(stroke
				(width 0.1524)
				(type default)
			)
			(layer "B.SilkS")
		)
		(fp_line
			(start -0.67945 -0.3048)
			(end -0.67945 0.3048)
			(stroke
				(width 0.1)
				(type default)
			)
			(layer "B.Fab")
		)
		(fp_line
			(start -0.67945 0.3048)
			(end -0.120396 0.3048)
			(stroke
				(width 0.1)
				(type default)
			)
			(layer "B.Fab")
		)
		(fp_line
			(start -0.12065 -0.3048)
			(end -0.67945 -0.3048)
			(stroke
				(width 0.1)
				(type default)
			)
			(layer "B.Fab")
		)
		(fp_line
			(start -0.12065 -0.2794)
			(end -0.12065 -0.3048)
			(stroke
				(width 0.1)
				(type default)
			)
			(layer "B.Fab")
		)
		(fp_line
			(start -0.120396 0.2794)
			(end 0.12065 0.2794)
			(stroke
				(width 0.1)
				(type default)
			)
			(layer "B.Fab")
		)
		(fp_line
			(start -0.120396 0.3048)
			(end -0.120396 0.2794)
			(stroke
				(width 0.1)
				(type default)
			)
			(layer "B.Fab")
		)
		(fp_line
			(start 0.12065 -0.305054)
			(end 0.12065 -0.2794)
			(stroke
				(width 0.1)
				(type default)
			)
			(layer "B.Fab")
		)
		(fp_line
			(start 0.12065 -0.2794)
			(end -0.12065 -0.2794)
			(stroke
				(width 0.1)
				(type default)
			)
			(layer "B.Fab")
		)
		(fp_line
			(start 0.12065 0.2794)
			(end 0.12065 0.3048)
			(stroke
				(width 0.1)
				(type default)
			)
			(layer "B.Fab")
		)
		(fp_line
			(start 0.12065 0.3048)
			(end 0.67945 0.3048)
			(stroke
				(width 0.1)
				(type default)
			)
			(layer "B.Fab")
		)
		(fp_line
			(start 0.67945 -0.305054)
			(end 0.12065 -0.305054)
			(stroke
				(width 0.1)
				(type default)
			)
			(layer "B.Fab")
		)
		(fp_line
			(start 0.67945 0.3048)
			(end 0.67945 -0.305054)
			(stroke
				(width 0.1)
				(type default)
			)
			(layer "B.Fab")
		)
		(pad "1" smd circle
			(at 0.40005 0 180)
			(size 0 0)
			(layers "B.Cu" "B.Mask" "B.Paste")
			(net "PGPPA_BMC_AUX_SENSOR")
		)
		(pad "2" smd circle
			(at -0.40005 0 180)
			(size 0 0)
			(layers "B.Cu" "B.Mask" "B.Paste")
			(net "GND")
		)
	)
	(footprint ""
		(layer "B.Cu")
		(at 23.85949 -97.187004)
		(property "Reference" "C188"
			(at 0 0 0)
			(layer "B.SilkS")
			(hide yes)
			(effects
				(font
					(size 1.27 1.27)
				)
				(justify mirror)
			)
		)
		(property "Value" ""
			(at 0 0 0)
			(layer "B.Fab")
			(effects
				(font
					(size 1.27 1.27)
				)
				(justify mirror)
			)
		)
		(duplicate_pad_numbers_are_jumpers no)
		(fp_line
			(start -0.69215 -0.2921)
			(end -0.69215 0.2921)
			(stroke
				(width 0.1524)
				(type default)
			)
			(layer "B.SilkS")
		)
		(fp_line
			(start -0.69215 0.2921)
			(end 0.69215 0.2921)
			(stroke
				(width 0.1524)
				(type default)
			)
			(layer "B.SilkS")
		)
		(fp_line
			(start 0.69215 -0.2921)
			(end -0.69215 -0.2921)
			(stroke
				(width 0.1524)
				(type default)
			)
			(layer "B.SilkS")
		)
		(fp_line
			(start 0.69215 0.2921)
			(end 0.69215 -0.2921)
			(stroke
				(width 0.1524)
				(type default)
			)
			(layer "B.SilkS")
		)
		(fp_line
			(start -0.51435 -0.2794)
			(end -0.51435 0.2794)
			(stroke
				(width 0.1)
				(type default)
			)
			(layer "B.Fab")
		)
		(fp_line
			(start -0.51435 0.2794)
			(end 0.51435 0.2794)
			(stroke
				(width 0.1)
				(type default)
			)
			(layer "B.Fab")
		)
		(fp_line
			(start 0.51435 -0.2794)
			(end -0.51435 -0.2794)
			(stroke
				(width 0.1)
				(type default)
			)
			(layer "B.Fab")
		)
		(fp_line
			(start 0.51435 0.2794)
			(end 0.51435 -0.2794)
			(stroke
				(width 0.1)
				(type default)
			)
			(layer "B.Fab")
		)
		(pad "1" smd circle
			(at 0.40005 0 180)
			(size 0 0)
			(layers "B.Cu" "B.Mask" "B.Paste")
			(net "VCCIO2")
		)
		(pad "2" smd circle
			(at -0.40005 0 180)
			(size 0 0)
			(layers "B.Cu" "B.Mask" "B.Paste")
			(net "GND")
		)
		(zone
			(layer "B.Cu")
			(hatch none 0.5)
			(connect_pads
				(clearance 0)
			)
			(min_thickness 0.25)
			(keepout
				(tracks not_allowed)
				(vias allowed)
				(pads allowed)
				(copperpour not_allowed)
				(footprints allowed)
			)
			(placement
				(enabled no)
				(sheetname "")
			)
			(fill
				(thermal_gap 0.5)
				(thermal_bridge_width 0.5)
				(island_removal_mode 0)
			)
			(polygon
				(pts
					(xy 24.04999 -97.099374) (xy 23.95855 -97.041208) (xy 23.75916 -97.041208) (xy 23.66899 -97.099374)
					(xy 23.66899 -97.274634) (xy 23.75916 -97.333054) (xy 23.95855 -97.333054) (xy 24.04999 -97.274888)
				)
			)
		)
	)
	(footprint ""
		(layer "B.Cu")
		(at 28.575 -32.385 90)
		(property "Reference" "C205"
			(at 0 0 90)
			(layer "B.SilkS")
			(hide yes)
			(effects
				(font
					(size 1.27 1.27)
				)
				(justify mirror)
			)
		)
		(property "Value" ""
			(at 0 0 90)
			(layer "B.Fab")
			(effects
				(font
					(size 1.27 1.27)
				)
				(justify mirror)
			)
		)
		(duplicate_pad_numbers_are_jumpers no)
		(fp_line
			(start 0.7874 -0.4064)
			(end -0.7874 -0.4064)
			(stroke
				(width 0.1524)
				(type default)
			)
			(layer "B.SilkS")
		)
		(fp_line
			(start -0.7874 -0.4064)
			(end -0.7874 0.4064)
			(stroke
				(width 0.1524)
				(type default)
			)
			(layer "B.SilkS")
		)
		(fp_line
			(start 0.7874 0.4064)
			(end 0.7874 -0.4064)
			(stroke
				(width 0.1524)
				(type default)
			)
			(layer "B.SilkS")
		)
		(fp_line
			(start -0.7874 0.4064)
			(end 0.7874 0.4064)
			(stroke
				(width 0.1524)
				(type default)
			)
			(layer "B.SilkS")
		)
		(fp_line
			(start 0.67945 -0.305054)
			(end 0.12065 -0.305054)
			(stroke
				(width 0.1)
				(type default)
			)
			(layer "B.Fab")
		)
		(fp_line
			(start 0.12065 -0.305054)
			(end 0.12065 -0.2794)
			(stroke
				(width 0.1)
				(type default)
			)
			(layer "B.Fab")
		)
		(fp_line
			(start -0.12065 -0.3048)
			(end -0.67945 -0.3048)
			(stroke
				(width 0.1)
				(type default)
			)
			(layer "B.Fab")
		)
		(fp_line
			(start -0.67945 -0.3048)
			(end -0.67945 0.3048)
			(stroke
				(width 0.1)
				(type default)
			)
			(layer "B.Fab")
		)
		(fp_line
			(start 0.12065 -0.2794)
			(end -0.12065 -0.2794)
			(stroke
				(width 0.1)
				(type default)
			)
			(layer "B.Fab")
		)
		(fp_line
			(start -0.12065 -0.2794)
			(end -0.12065 -0.3048)
			(stroke
				(width 0.1)
				(type default)
			)
			(layer "B.Fab")
		)
		(fp_line
			(start 0.12065 0.2794)
			(end 0.12065 0.3048)
			(stroke
				(width 0.1)
				(type default)
			)
			(layer "B.Fab")
		)
		(fp_line
			(start -0.120396 0.2794)
			(end 0.12065 0.2794)
			(stroke
				(width 0.1)
				(type default)
			)
			(layer "B.Fab")
		)
		(fp_line
			(start 0.67945 0.3048)
			(end 0.67945 -0.305054)
			(stroke
				(width 0.1)
				(type default)
			)
			(layer "B.Fab")
		)
		(fp_line
			(start 0.12065 0.3048)
			(end 0.67945 0.3048)
			(stroke
				(width 0.1)
				(type default)
			)
			(layer "B.Fab")
		)
		(fp_line
			(start -0.120396 0.3048)
			(end -0.120396 0.2794)
			(stroke
				(width 0.1)
				(type default)
			)
			(layer "B.Fab")
		)
		(fp_line
			(start -0.67945 0.3048)
			(end -0.120396 0.3048)
			(stroke
				(width 0.1)
				(type default)
			)
			(layer "B.Fab")
		)
		(pad "1" smd circle
			(at 0.40005 0 270)
			(size 0 0)
			(layers "B.Cu" "B.Mask" "B.Paste")
			(net "V_DACR")
		)
		(pad "2" smd circle
			(at -0.40005 0 270)
			(size 0 0)
			(layers "B.Cu" "B.Mask" "B.Paste")
			(net "GND")
		)
	)
	(footprint ""
		(layer "B.Cu")
		(at 53.291994 -69.397372 -90)
		(property "Reference" "C303"
			(at 0 0 90)
			(layer "B.SilkS")
			(hide yes)
			(effects
				(font
					(size 1.27 1.27)
				)
				(justify mirror)
			)
		)
		(property "Value" ""
			(at 0 0 90)
			(layer "B.Fab")
			(effects
				(font
					(size 1.27 1.27)
				)
				(justify mirror)
			)
		)
		(duplicate_pad_numbers_are_jumpers no)
		(fp_line
			(start -0.7874 0.4064)
			(end 0.7874 0.4064)
			(stroke
				(width 0.1524)
				(type default)
			)
			(layer "B.SilkS")
		)
		(fp_line
			(start 0.7874 0.4064)
			(end 0.7874 -0.4064)
			(stroke
				(width 0.1524)
				(type default)
			)
			(layer "B.SilkS")
		)
		(fp_line
			(start -0.7874 -0.4064)
			(end -0.7874 0.4064)
			(stroke
				(width 0.1524)
				(type default)
			)
			(layer "B.SilkS")
		)
		(fp_line
			(start 0.7874 -0.4064)
			(end -0.7874 -0.4064)
			(stroke
				(width 0.1524)
				(type default)
			)
			(layer "B.SilkS")
		)
		(fp_line
			(start -0.67945 0.3048)
			(end -0.120396 0.3048)
			(stroke
				(width 0.1)
				(type default)
			)
			(layer "B.Fab")
		)
		(fp_line
			(start -0.120396 0.3048)
			(end -0.120396 0.2794)
			(stroke
				(width 0.1)
				(type default)
			)
			(layer "B.Fab")
		)
		(fp_line
			(start 0.12065 0.3048)
			(end 0.67945 0.3048)
			(stroke
				(width 0.1)
				(type default)
			)
			(layer "B.Fab")
		)
		(fp_line
			(start 0.67945 0.3048)
			(end 0.67945 -0.305054)
			(stroke
				(width 0.1)
				(type default)
			)
			(layer "B.Fab")
		)
		(fp_line
			(start -0.120396 0.2794)
			(end 0.12065 0.2794)
			(stroke
				(width 0.1)
				(type default)
			)
			(layer "B.Fab")
		)
		(fp_line
			(start 0.12065 0.2794)
			(end 0.12065 0.3048)
			(stroke
				(width 0.1)
				(type default)
			)
			(layer "B.Fab")
		)
		(fp_line
			(start -0.12065 -0.2794)
			(end -0.12065 -0.3048)
			(stroke
				(width 0.1)
				(type default)
			)
			(layer "B.Fab")
		)
		(fp_line
			(start 0.12065 -0.2794)
			(end -0.12065 -0.2794)
			(stroke
				(width 0.1)
				(type default)
			)
			(layer "B.Fab")
		)
		(fp_line
			(start -0.67945 -0.3048)
			(end -0.67945 0.3048)
			(stroke
				(width 0.1)
				(type default)
			)
			(layer "B.Fab")
		)
		(fp_line
			(start -0.12065 -0.3048)
			(end -0.67945 -0.3048)
			(stroke
				(width 0.1)
				(type default)
			)
			(layer "B.Fab")
		)
		(fp_line
			(start 0.12065 -0.305054)
			(end 0.12065 -0.2794)
			(stroke
				(width 0.1)
				(type default)
			)
			(layer "B.Fab")
		)
		(fp_line
			(start 0.67945 -0.305054)
			(end 0.12065 -0.305054)
			(stroke
				(width 0.1)
				(type default)
			)
			(layer "B.Fab")
		)
		(pad "1" smd circle
			(at 0.40005 0 90)
			(size 0 0)
			(layers "B.Cu" "B.Mask" "B.Paste")
			(net "P2V5_SENSOR")
		)
		(pad "2" smd circle
			(at -0.40005 0 90)
			(size 0 0)
			(layers "B.Cu" "B.Mask" "B.Paste")
			(net "GND")
		)
	)
	(footprint ""
		(layer "B.Cu")
		(at 54.483 -34.671 90)
		(property "Reference" "R580"
			(at 0 0 90)
			(layer "B.SilkS")
			(hide yes)
			(effects
				(font
					(size 1.27 1.27)
				)
				(justify mirror)
			)
		)
		(property "Value" ""
			(at 0 0 90)
			(layer "B.Fab")
			(effects
				(font
					(size 1.27 1.27)
				)
				(justify mirror)
			)
		)
		(duplicate_pad_numbers_are_jumpers no)
		(fp_line
			(start 0.7874 -0.4064)
			(end -0.7874 -0.4064)
			(stroke
				(width 0.1524)
				(type default)
			)
			(layer "B.SilkS")
		)
		(fp_line
			(start -0.7874 -0.4064)
			(end -0.7874 0.4064)
			(stroke
				(width 0.1524)
				(type default)
			)
			(layer "B.SilkS")
		)
		(fp_line
			(start 0.7874 0.4064)
			(end 0.7874 -0.4064)
			(stroke
				(width 0.1524)
				(type default)
			)
			(layer "B.SilkS")
		)
		(fp_line
			(start -0.7874 0.4064)
			(end 0.7874 0.4064)
			(stroke
				(width 0.1524)
				(type default)
			)
			(layer "B.SilkS")
		)
		(fp_line
			(start 0.67945 -0.305054)
			(end 0.12065 -0.305054)
			(stroke
				(width 0.1)
				(type default)
			)
			(layer "B.Fab")
		)
		(fp_line
			(start 0.12065 -0.305054)
			(end 0.12065 -0.2794)
			(stroke
				(width 0.1)
				(type default)
			)
			(layer "B.Fab")
		)
		(fp_line
			(start -0.12065 -0.3048)
			(end -0.67945 -0.3048)
			(stroke
				(width 0.1)
				(type default)
			)
			(layer "B.Fab")
		)
		(fp_line
			(start -0.67945 -0.3048)
			(end -0.67945 0.3048)
			(stroke
				(width 0.1)
				(type default)
			)
			(layer "B.Fab")
		)
		(fp_line
			(start 0.12065 -0.2794)
			(end -0.12065 -0.2794)
			(stroke
				(width 0.1)
				(type default)
			)
			(layer "B.Fab")
		)
		(fp_line
			(start -0.12065 -0.2794)
			(end -0.12065 -0.3048)
			(stroke
				(width 0.1)
				(type default)
			)
			(layer "B.Fab")
		)
		(fp_line
			(start 0.12065 0.2794)
			(end 0.12065 0.3048)
			(stroke
				(width 0.1)
				(type default)
			)
			(layer "B.Fab")
		)
		(fp_line
			(start -0.120396 0.2794)
			(end 0.12065 0.2794)
			(stroke
				(width 0.1)
				(type default)
			)
			(layer "B.Fab")
		)
		(fp_line
			(start 0.67945 0.3048)
			(end 0.67945 -0.305054)
			(stroke
				(width 0.1)
				(type default)
			)
			(layer "B.Fab")
		)
		(fp_line
			(start 0.12065 0.3048)
			(end 0.67945 0.3048)
			(stroke
				(width 0.1)
				(type default)
			)
			(layer "B.Fab")
		)
		(fp_line
			(start -0.120396 0.3048)
			(end -0.120396 0.2794)
			(stroke
				(width 0.1)
				(type default)
			)
			(layer "B.Fab")
		)
		(fp_line
			(start -0.67945 0.3048)
			(end -0.120396 0.3048)
			(stroke
				(width 0.1)
				(type default)
			)
			(layer "B.Fab")
		)
		(pad "1" smd circle
			(at 0.40005 0 270)
			(size 0 0)
			(layers "B.Cu" "B.Mask" "B.Paste")
			(net "SMB_BMC_MM9_R_SCL")
		)
		(pad "2" smd circle
			(at -0.40005 0 270)
			(size 0 0)
			(layers "B.Cu" "B.Mask" "B.Paste")
			(net "SMB_BMC_MM9_SCL")
		)
	)
)
